# S9S_MB_2U (Grand Teton) — schematic netlist excerpt (pin names and nets, part order shuffled) for the footprints in the layout excerpt that follows; sources: Cadence DE-HDL packaged netlist, KiCad conversion of 03242023_DA0F0TMBIJ0_F0T_Motherboard_J_brd_V01_OCP.brd

R3797  Q_RES  100K 1% EMPTY  pkg 0402LF  page 156 : A = P3V3_AUX ; B = HP_LVC3_OCP_V3_1_P12V_PWRGD
C2363  Q_CAP  0.1UF 25V 10% EMPTY  pkg 0402  page 251 : A = HSC_TYPE_ADC ; B = GND

(kicad_pcb
	(version 20260206)
	(generator "pcbnew")
	(generator_version "10.0")
	(general
		(thickness 1.6)
		(legacy_teardrops no)
	)
	(paper "A4")
	(title_block
		(title "03242023_DA0F0TMBIJ0_F0T_Motherboard_J_brd_V01_OCP.brd")
		(comment 1 "Grand Teton / footprints 3309-3310 of 6105")
	)
	(layers
		(0 "F.Cu" signal "TOP")
		(4 "In1.Cu" signal "GND")
		(6 "In2.Cu" signal "IN1")
		(8 "In3.Cu" signal "GND1")
		(10 "In4.Cu" signal "IN2")
		(12 "In5.Cu" signal "GND2")
		(14 "In6.Cu" signal "IN3")
		(16 "In7.Cu" signal "GND3")
		(18 "In8.Cu" signal "VCC")
		(20 "In9.Cu" signal "VCC1")
		(22 "In10.Cu" signal "GND4")
		(24 "In11.Cu" signal "IN4")
		(26 "In12.Cu" signal "GND5")
		(28 "In13.Cu" signal "IN5")
		(30 "In14.Cu" signal "GND6")
		(32 "In15.Cu" signal "IN6")
		(34 "In16.Cu" signal "GND7")
		(2 "B.Cu" signal "BOTTOM")
		(9 "F.Adhes" user "F.Adhesive")
		(11 "B.Adhes" user "B.Adhesive")
		(13 "F.Paste" user "Package Geometry/Pastemask Top")
		(15 "B.Paste" user "Package Geometry/Pastemask Bottom")
		(5 "F.SilkS" user "Ref Des/Silkscreen Top")
		(7 "B.SilkS" user "Ref Des/Silkscreen Bottom")
		(1 "F.Mask" user "Board Geometry/Soldermask Top")
		(3 "B.Mask" user "Board Geometry/Soldermask Bottom")
		(17 "Dwgs.User" user "User.Drawings")
		(19 "Cmts.User" user "User.Comments")
		(21 "Eco1.User" user "User.Eco1")
		(23 "Eco2.User" user "User.Eco2")
		(25 "Edge.Cuts" user "Board Geometry/Outline")
		(27 "Margin" user)
		(31 "F.CrtYd" user "Package Geometry/Place Bound Top")
		(29 "B.CrtYd" user "Package Geometry/Place Bound Bottom")
		(35 "F.Fab" user "Ref Des/Assembly Top")
		(33 "B.Fab" user "Ref Des/Assembly Bottom")
	)
	(footprint ""
		(layer "F.Cu")
		(at 300.99762 -413.756094 90)
		(property "Reference" "C2363"
			(at 0 0 90)
			(layer "F.SilkS")
			(hide yes)
			(effects
				(font
					(size 1.27 1.27)
				)
			)
		)
		(property "Value" ""
			(at 0 0 90)
			(layer "F.Fab")
			(effects
				(font
					(size 1.27 1.27)
				)
			)
		)
		(duplicate_pad_numbers_are_jumpers no)
		(fp_line
			(start 0.7874 -0.4064)
			(end 0.7874 0.4064)
			(stroke
				(width 0.1524)
				(type default)
			)
			(layer "F.SilkS")
		)
		(fp_line
			(start -0.7874 -0.4064)
			(end 0.7874 -0.4064)
			(stroke
				(width 0.1524)
				(type default)
			)
			(layer "F.SilkS")
		)
		(fp_line
			(start 0.7874 0.4064)
			(end -0.7874 0.4064)
			(stroke
				(width 0.1524)
				(type default)
			)
			(layer "F.SilkS")
		)
		(fp_line
			(start -0.7874 0.4064)
			(end -0.7874 -0.4064)
			(stroke
				(width 0.1524)
				(type default)
			)
			(layer "F.SilkS")
		)
		(fp_line
			(start -0.12065 -0.305054)
			(end -0.12065 -0.2794)
			(stroke
				(width 0.1)
				(type default)
			)
			(layer "F.Fab")
		)
		(fp_line
			(start -0.67945 -0.305054)
			(end -0.12065 -0.305054)
			(stroke
				(width 0.1)
				(type default)
			)
			(layer "F.Fab")
		)
		(fp_line
			(start 0.67945 -0.3048)
			(end 0.67945 0.3048)
			(stroke
				(width 0.1)
				(type default)
			)
			(layer "F.Fab")
		)
		(fp_line
			(start 0.12065 -0.3048)
			(end 0.67945 -0.3048)
			(stroke
				(width 0.1)
				(type default)
			)
			(layer "F.Fab")
		)
		(fp_line
			(start 0.12065 -0.2794)
			(end 0.12065 -0.3048)
			(stroke
				(width 0.1)
				(type default)
			)
			(layer "F.Fab")
		)
		(fp_line
			(start -0.12065 -0.2794)
			(end 0.12065 -0.2794)
			(stroke
				(width 0.1)
				(type default)
			)
			(layer "F.Fab")
		)
		(fp_line
			(start 0.120396 0.2794)
			(end -0.12065 0.2794)
			(stroke
				(width 0.1)
				(type default)
			)
			(layer "F.Fab")
		)
		(fp_line
			(start -0.12065 0.2794)
			(end -0.12065 0.3048)
			(stroke
				(width 0.1)
				(type default)
			)
			(layer "F.Fab")
		)
		(fp_line
			(start 0.67945 0.3048)
			(end 0.120396 0.3048)
			(stroke
				(width 0.1)
				(type default)
			)
			(layer "F.Fab")
		)
		(fp_line
			(start 0.120396 0.3048)
			(end 0.120396 0.2794)
			(stroke
				(width 0.1)
				(type default)
			)
			(layer "F.Fab")
		)
		(fp_line
			(start -0.12065 0.3048)
			(end -0.67945 0.3048)
			(stroke
				(width 0.1)
				(type default)
			)
			(layer "F.Fab")
		)
		(fp_line
			(start -0.67945 0.3048)
			(end -0.67945 -0.305054)
			(stroke
				(width 0.1)
				(type default)
			)
			(layer "F.Fab")
		)
		(pad "1" smd circle
			(at -0.40005 0 90)
			(size 0 0)
			(layers "F.Cu" "F.Mask" "F.Paste")
			(net "HSC_TYPE_ADC")
		)
		(pad "2" smd circle
			(at 0.40005 0 90)
			(size 0 0)
			(layers "F.Cu" "F.Mask" "F.Paste")
			(net "GND")
		)
	)
	(footprint ""
		(layer "F.Cu")
		(at 454.847452 -19.427698 -90)
		(property "Reference" "R3797"
			(at 0 0 270)
			(layer "F.SilkS")
			(hide yes)
			(effects
				(font
					(size 1.27 1.27)
				)
			)
		)
		(property "Value" ""
			(at 0 0 270)
			(layer "F.Fab")
			(effects
				(font
					(size 1.27 1.27)
				)
			)
		)
		(duplicate_pad_numbers_are_jumpers no)
		(fp_line
			(start -0.7874 0.4064)
			(end -0.7874 -0.4064)
			(stroke
				(width 0.1524)
				(type default)
			)
			(layer "F.SilkS")
		)
		(fp_line
			(start 0.7874 0.4064)
			(end -0.7874 0.4064)
			(stroke
				(width 0.1524)
				(type default)
			)
			(layer "F.SilkS")
		)
		(fp_line
			(start -0.7874 -0.4064)
			(end 0.7874 -0.4064)
			(stroke
				(width 0.1524)
				(type default)
			)
			(layer "F.SilkS")
		)
		(fp_line
			(start 0.7874 -0.4064)
			(end 0.7874 0.4064)
			(stroke
				(width 0.1524)
				(type default)
			)
			(layer "F.SilkS")
		)
		(fp_line
			(start -0.67945 0.3048)
			(end -0.67945 -0.305054)
			(stroke
				(width 0.1)
				(type default)
			)
			(layer "F.Fab")
		)
		(fp_line
			(start -0.12065 0.3048)
			(end -0.67945 0.3048)
			(stroke
				(width 0.1)
				(type default)
			)
			(layer "F.Fab")
		)
		(fp_line
			(start 0.120396 0.3048)
			(end 0.120396 0.2794)
			(stroke
				(width 0.1)
				(type default)
			)
			(layer "F.Fab")
		)
		(fp_line
			(start 0.67945 0.3048)
			(end 0.120396 0.3048)
			(stroke
				(width 0.1)
				(type default)
			)
			(layer "F.Fab")
		)
		(fp_line
			(start -0.12065 0.2794)
			(end -0.12065 0.3048)
			(stroke
				(width 0.1)
				(type default)
			)
			(layer "F.Fab")
		)
		(fp_line
			(start 0.120396 0.2794)
			(end -0.12065 0.2794)
			(stroke
				(width 0.1)
				(type default)
			)
			(layer "F.Fab")
		)
		(fp_line
			(start -0.12065 -0.2794)
			(end 0.12065 -0.2794)
			(stroke
				(width 0.1)
				(type default)
			)
			(layer "F.Fab")
		)
		(fp_line
			(start 0.12065 -0.2794)
			(end 0.12065 -0.3048)
			(stroke
				(width 0.1)
				(type default)
			)
			(layer "F.Fab")
		)
		(fp_line
			(start 0.12065 -0.3048)
			(end 0.67945 -0.3048)
			(stroke
				(width 0.1)
				(type default)
			)
			(layer "F.Fab")
		)
		(fp_line
			(start 0.67945 -0.3048)
			(end 0.67945 0.3048)
			(stroke
				(width 0.1)
				(type default)
			)
			(layer "F.Fab")
		)
		(fp_line
			(start -0.67945 -0.305054)
			(end -0.12065 -0.305054)
			(stroke
				(width 0.1)
				(type default)
			)
			(layer "F.Fab")
		)
		(fp_line
			(start -0.12065 -0.305054)
			(end -0.12065 -0.2794)
			(stroke
				(width 0.1)
				(type default)
			)
			(layer "F.Fab")
		)
		(pad "1" smd circle
			(at -0.40005 0 270)
			(size 0 0)
			(layers "F.Cu" "F.Mask" "F.Paste")
			(net "P3V3_AUX")
		)
		(pad "2" smd circle
			(at 0.40005 0 270)
			(size 0 0)
			(layers "F.Cu" "F.Mask" "F.Paste")
			(net "HP_LVC3_OCP_V3_1_P12V_PWRGD")
		)
	)
)
